FILE_TYPE = MACRO_DRAWING;
SET COLOR_WIRE YELLOW;
SET COLOR_PROP ORANGE;
SET COLOR_DOT WHITE;
SET COLOR_ARC YELLOW;
SET COLOR_BODY GREEN;
SET COLOR_NOTE PURPLE;
SET PROP_DISPLAY VALUE;
SET PAGE_NUMBER P4;
FORCEADD SHEET_A1..1
(-200 2050);
FORCEPROP 2 LAST CUSTOM_TXT_CDS <XR_PAGE_TITLE>
J 0
(-15770 13400);
DISPLAY 0.638298 (-15770 13400);
PAINT PINK (-15770 13400);
FORCEPROP 1 LAST CUSTOM_TXT_CDS <DOCNO>
J 0
(-2250 2435);
DISPLAY 0.978723 (-2250 2435);
FORCEPROP 1 LAST CUSTOM_TXT_CDS <CON_PAGE_NUM>
J 0
(-2355 2100);
DISPLAY 0.978723 (-2355 2100);
FORCEPROP 1 LAST CUSTOM_TXT_CDS <DATE>
J 0
(-900 2225);
DISPLAY 0.978723 (-900 2225);
FORCEPROP 1 LAST CUSTOM_TXT_CDS <TITLE>
J 1
(-1985 2680);
DISPLAY 0.978723 (-1985 2680);
FORCEPROP 1 LAST CUSTOM_TXT_CDS <DESIGNER>
J 0
(-900 2650);
DISPLAY 0.978723 (-900 2650);
FORCEPROP 1 LAST CUSTOM_TXT_CDS <CON_TOTAL_PAGES>
J 0
(-2045 2100);
DISPLAY 0.808511 (-2045 2100);
FORCEPROP 1 LAST CUSTOM_TXT_CDS <ASSY_PN>
J 0
(-2250 2225);
DISPLAY 0.978723 (-2250 2225);
FORCEPROP 1 LAST CUSTOM_TXT_CDS <DOCREV>
J 0
(-900 2425);
DISPLAY 0.978723 (-900 2425);
FORCEPROP 2 LAST CDS_XR_PAGE_TITLE CR-5 : @TIMECARD_LIB.TIMECARD(SCH_1):PAGE5
J 0
(-15770 13400);
DISPLAY 0.638298 (-15770 13400);
PAINT PINK (-15770 13400);
DISPLAY INVISIBLE (-15770 13400);
FORCEPROP 2 LAST CDS_LIB cls
J 0
(-200 2050);
DISPLAY INVISIBLE (-200 2050);
FORCEPROP 1 LAST CDS_LMAN_SYM_OUTLINE -15850,11500,200,-200
J 0
(-200 2050);
DISPLAY 0.468085 (-200 2050);
PAINT GREEN (-200 2050);
DISPLAY INVISIBLE (-200 2050);
FORCEPROP 2 LAST PAGE_BORDER TRUE
J 0
(-15770 13400);
DISPLAY 0.638298 (-15770 13400);
PAINT PINK (-15770 13400);
DISPLAY INVISIBLE (-15770 13400);
FORCEPROP 1 LAST COMMENT_BODY TRUE
J 0
(-190 2105);
DISPLAY 0.808511 (-190 2105);
DISPLAY INVISIBLE (-190 2105);
FORCEPROP 1 LAST TITLE USB2UART/MPSSE_CONNECTION_DIAGRAM
J 0
(-200 2050);
PAINT MONO (-200 2050);
DISPLAY INVISIBLE (-200 2050);
FORCENOTE
USB2UART/MPSSE_CONNECTION_DIAGRAM
(-10950 12150) 0;
DISPLAY LEFT (-10950 12150);
DISPLAY 3.936170 (-10950 12150);
FORCENOTE
$CDS_IMAGE|clipboard_0_13.jpg|10468|6454
(-7775 8000) 0;
DISPLAY LEFT (-7775 8000);
QUIT
